(kicad_pcb
	(version 20260206)
	(generator "pcbnew")
	(generator_version "10.0")
	(general
		(thickness 1.6)
		(legacy_teardrops no)
	)
	(paper "A4")
	(title_block
		(title "Bryce Canyon_IOM_M2_16342-2_OCP.brd")
		(comment 1 "Bryce Canyon / footprints 734-740 of 1146")
	)
	(layers
		(0 "F.Cu" signal "TOP")
		(4 "In1.Cu" signal "L2GND")
		(6 "In2.Cu" signal "L3")
		(8 "In3.Cu" signal "L4VCC")
		(10 "In4.Cu" signal "L5VCC")
		(12 "In5.Cu" signal "L6")
		(14 "In6.Cu" signal "L7GND")
		(2 "B.Cu" signal "BOTTOM")
		(9 "F.Adhes" user "F.Adhesive")
		(11 "B.Adhes" user "B.Adhesive")
		(13 "F.Paste" user "Package Geometry/Pastemask Top")
		(15 "B.Paste" user "Package Geometry/Pastemask Bottom")
		(5 "F.SilkS" user "Ref Des/Silkscreen Top")
		(7 "B.SilkS" user "Ref Des/Silkscreen Bottom")
		(1 "F.Mask" user "Board Geometry/Soldermask Top")
		(3 "B.Mask" user "Board Geometry/Soldermask Bottom")
		(17 "Dwgs.User" user "User.Drawings")
		(19 "Cmts.User" user "User.Comments")
		(21 "Eco1.User" user "User.Eco1")
		(23 "Eco2.User" user "User.Eco2")
		(25 "Edge.Cuts" user "Board Geometry/Outline")
		(27 "Margin" user)
		(31 "F.CrtYd" user "Package Geometry/Place Bound Top")
		(29 "B.CrtYd" user "Package Geometry/Place Bound Bottom")
		(35 "F.Fab" user "Ref Des/Assembly Top")
		(33 "B.Fab" user "Ref Des/Assembly Bottom")
	)
	(footprint ""
		(layer "B.Cu")
		(at 43.3832 -128.2192)
		(property "Reference" "R270"
			(at 0 0 0)
			(layer "B.SilkS")
			(hide yes)
			(effects
				(font
					(size 1.27 1.27)
				)
				(justify mirror)
			)
		)
		(property "Value" "33R2F-3-GP"
			(at -0.064008 -3.993896 0)
			(unlocked yes)
			(layer "B.Fab")
			(hide yes)
			(effects
				(font
					(size 1.016 1.016)
					(thickness 0.1524)
				)
				(justify mirror)
			)
		)
		(property "Device Type" "R402H16"
			(at -0.064008 -5.517896 0)
			(unlocked yes)
			(layer "B.Fab")
			(hide yes)
			(effects
				(font
					(size 1.016 1.016)
					(thickness 0.1524)
				)
				(justify mirror)
			)
		)
		(duplicate_pad_numbers_are_jumpers no)
		(fp_line
			(start -0.508 -0.9398)
			(end 0.508 -0.9398)
			(stroke
				(width 0.1524)
				(type default)
			)
			(layer "B.SilkS")
		)
		(fp_line
			(start 0.508 -0.9398)
			(end 0.508 0.9398)
			(stroke
				(width 0.1524)
				(type default)
			)
			(layer "B.SilkS")
		)
		(fp_rect
			(start 0.508 0.9398)
			(end -0.508 -0.9398)
			(stroke
				(width 0)
				(type default)
			)
			(fill no)
			(layer "B.CrtYd")
		)
		(fp_rect
			(start 0.508 0.9398)
			(end -0.508 -0.9398)
			(stroke
				(width 0)
				(type default)
			)
			(fill no)
			(layer "B.Fab")
		)
		(pad "1" smd custom
			(at 0 -0.4445 180)
			(size 0.1397 0.1397)
			(layers "B.Cu" "B.Mask" "B.Paste")
			(net "BMC_SPI_MISO")
			(options
				(clearance outline)
				(anchor circle)
			)
			(primitives
				(gr_poly
					(pts
						(arc
							(start -0.1778 0.2794)
							(mid -0.249642 0.249642)
							(end -0.2794 0.1778)
						)
						(arc
							(start -0.2794 -0.1778)
							(mid -0.249642 -0.249642)
							(end -0.1778 -0.2794)
						)
						(arc
							(start 0.1778 -0.2794)
							(mid 0.249642 -0.249642)
							(end 0.2794 -0.1778)
						)
						(arc
							(start 0.2794 0.1778)
							(mid 0.249642 0.249642)
							(end 0.1778 0.2794)
						)
					)
					(width 0)
					(fill yes)
				)
			)
		)
		(pad "2" smd custom
			(at 0 0.4445 180)
			(size 0.1397 0.1397)
			(layers "B.Cu" "B.Mask" "B.Paste")
			(net "BMC_SPI_MISO_R")
			(options
				(clearance outline)
				(anchor circle)
			)
			(primitives
				(gr_poly
					(pts
						(arc
							(start -0.1778 0.2794)
							(mid -0.249642 0.249642)
							(end -0.2794 0.1778)
						)
						(arc
							(start -0.2794 -0.1778)
							(mid -0.249642 -0.249642)
							(end -0.1778 -0.2794)
						)
						(arc
							(start 0.1778 -0.2794)
							(mid 0.249642 -0.249642)
							(end 0.2794 -0.1778)
						)
						(arc
							(start 0.2794 0.1778)
							(mid 0.249642 0.249642)
							(end 0.1778 0.2794)
						)
					)
					(width 0)
					(fill yes)
				)
			)
		)
	)
	(footprint ""
		(layer "B.Cu")
		(at 73.224644 -148.73097)
		(property "Reference" "R50"
			(at 0 0 0)
			(layer "B.SilkS")
			(hide yes)
			(effects
				(font
					(size 1.27 1.27)
				)
				(justify mirror)
			)
		)
		(property "Value" "4K7R2F-GP"
			(at -0.064008 -3.993896 0)
			(unlocked yes)
			(layer "B.Fab")
			(hide yes)
			(effects
				(font
					(size 1.016 1.016)
					(thickness 0.1524)
				)
				(justify mirror)
			)
		)
		(property "Device Type" "R402H16"
			(at -0.064008 -5.517896 0)
			(unlocked yes)
			(layer "B.Fab")
			(hide yes)
			(effects
				(font
					(size 1.016 1.016)
					(thickness 0.1524)
				)
				(justify mirror)
			)
		)
		(duplicate_pad_numbers_are_jumpers no)
		(fp_line
			(start -0.508 -0.9398)
			(end 0.508 -0.9398)
			(stroke
				(width 0.1524)
				(type default)
			)
			(layer "B.SilkS")
		)
		(fp_line
			(start 0.508 -0.9398)
			(end 0.508 0.9398)
			(stroke
				(width 0.1524)
				(type default)
			)
			(layer "B.SilkS")
		)
		(fp_rect
			(start 0.508 0.9398)
			(end -0.508 -0.9398)
			(stroke
				(width 0)
				(type default)
			)
			(fill no)
			(layer "B.CrtYd")
		)
		(fp_rect
			(start 0.508 0.9398)
			(end -0.508 -0.9398)
			(stroke
				(width 0)
				(type default)
			)
			(fill no)
			(layer "B.Fab")
		)
		(pad "1" smd custom
			(at 0 -0.4445 180)
			(size 0.1397 0.1397)
			(layers "B.Cu" "B.Mask" "B.Paste")
			(net "P3V3_STBY")
			(options
				(clearance outline)
				(anchor circle)
			)
			(primitives
				(gr_poly
					(pts
						(arc
							(start -0.1778 0.2794)
							(mid -0.249642 0.249642)
							(end -0.2794 0.1778)
						)
						(arc
							(start -0.2794 -0.1778)
							(mid -0.249642 -0.249642)
							(end -0.1778 -0.2794)
						)
						(arc
							(start 0.1778 -0.2794)
							(mid 0.249642 -0.249642)
							(end 0.2794 -0.1778)
						)
						(arc
							(start 0.2794 0.1778)
							(mid 0.249642 0.249642)
							(end 0.1778 0.2794)
						)
					)
					(width 0)
					(fill yes)
				)
			)
		)
		(pad "2" smd custom
			(at 0 0.4445 180)
			(size 0.1397 0.1397)
			(layers "B.Cu" "B.Mask" "B.Paste")
			(net "I2C_DEBUG_SDA")
			(options
				(clearance outline)
				(anchor circle)
			)
			(primitives
				(gr_poly
					(pts
						(arc
							(start -0.1778 0.2794)
							(mid -0.249642 0.249642)
							(end -0.2794 0.1778)
						)
						(arc
							(start -0.2794 -0.1778)
							(mid -0.249642 -0.249642)
							(end -0.1778 -0.2794)
						)
						(arc
							(start 0.1778 -0.2794)
							(mid 0.249642 -0.249642)
							(end 0.2794 -0.1778)
						)
						(arc
							(start 0.2794 0.1778)
							(mid 0.249642 0.249642)
							(end 0.1778 0.2794)
						)
					)
					(width 0)
					(fill yes)
				)
			)
		)
	)
	(footprint ""
		(layer "B.Cu")
		(at 91.94292 -135.2296 -90)
		(property "Reference" "U101"
			(at 0 0 90)
			(layer "B.SilkS")
			(hide yes)
			(effects
				(font
					(size 1.27 1.27)
				)
				(justify mirror)
			)
		)
		(property "Value" "SNLVC1G126DCKR-GP"
			(at 2.3368 -8.6868 270)
			(unlocked yes)
			(layer "B.Fab")
			(hide yes)
			(effects
				(font
					(size 1.016 1.016)
					(thickness 0.1524)
				)
				(justify mirror)
			)
		)
		(property "Device Type" "SC70-5H44"
			(at 2.3114 -10.414 270)
			(unlocked yes)
			(layer "B.Fab")
			(hide yes)
			(effects
				(font
					(size 1.016 1.016)
					(thickness 0.1524)
				)
				(justify mirror)
			)
		)
		(duplicate_pad_numbers_are_jumpers no)
		(fp_line
			(start -1.27 1.7018)
			(end 1.27 1.7018)
			(stroke
				(width 0.1524)
				(type default)
			)
			(layer "B.SilkS")
		)
		(fp_line
			(start 1.27 1.7018)
			(end 1.27 -1.7018)
			(stroke
				(width 0.1524)
				(type default)
			)
			(layer "B.SilkS")
		)
		(fp_line
			(start -1.27 -1.7018)
			(end -1.27 1.7018)
			(stroke
				(width 0.1524)
				(type default)
			)
			(layer "B.SilkS")
		)
		(fp_line
			(start 1.27 -1.7018)
			(end -1.27 -1.7018)
			(stroke
				(width 0.1524)
				(type default)
			)
			(layer "B.SilkS")
		)
		(fp_line
			(start -1.3843 -1.8034)
			(end -1.3843 -1.1176)
			(stroke
				(width 0.3302)
				(type default)
			)
			(layer "B.SilkS")
		)
		(fp_line
			(start -0.6604 -1.8034)
			(end -1.3843 -1.8034)
			(stroke
				(width 0.3302)
				(type default)
			)
			(layer "B.SilkS")
		)
		(fp_rect
			(start 1.524 1.9558)
			(end -1.524 -1.9558)
			(stroke
				(width 0)
				(type default)
			)
			(fill no)
			(layer "B.CrtYd")
		)
		(fp_poly
			(pts
				(xy 1.524 -1.9558) (xy -1.524 -1.9558) (xy -1.524 1.9558) (xy 1.524 1.9558)
			)
			(stroke
				(width 0)
				(type default)
			)
			(fill no)
			(layer "B.Fab")
		)
		(pad "1" smd rect
			(at -0.65024 -0.8255 90)
			(size 0.4064 1.2192)
			(layers "B.Cu" "B.Mask" "B.Paste")
			(net "DEBUG_CARD_PRSNT")
		)
		(pad "2" smd rect
			(at 0 -0.8255 90)
			(size 0.4064 1.2192)
			(layers "B.Cu" "B.Mask" "B.Paste")
			(net "UART_IOM_RX")
		)
		(pad "3" smd rect
			(at 0.65024 -0.8255 90)
			(size 0.4064 1.2192)
			(layers "B.Cu" "B.Mask" "B.Paste")
			(net "GND")
		)
		(pad "4" smd rect
			(at 0.65024 0.8255 90)
			(size 0.4064 1.2192)
			(layers "B.Cu" "B.Mask" "B.Paste")
			(net "DEBUG_UART_IOM_RX")
		)
		(pad "5" smd rect
			(at -0.65024 0.8255 90)
			(size 0.4064 1.2192)
			(layers "B.Cu" "B.Mask" "B.Paste")
			(net "P3V3_STBY")
		)
	)
	(footprint ""
		(layer "B.Cu")
		(at 50.105056 -151.599646)
		(property "Reference" "TP209"
			(at 0 0 0)
			(layer "B.SilkS")
			(hide yes)
			(effects
				(font
					(size 1.27 1.27)
				)
				(justify mirror)
			)
		)
		(property "Value" "TPAD28-2-GP"
			(at 0.0127 -1.6637 0)
			(unlocked yes)
			(layer "B.Fab")
			(hide yes)
			(effects
				(font
					(size 1.016 1.016)
					(thickness 0.1524)
				)
				(justify mirror)
			)
		)
		(property "Device Type" "TPAD28"
			(at 0.0127 -3.1877 0)
			(unlocked yes)
			(layer "B.Fab")
			(hide yes)
			(effects
				(font
					(size 1.016 1.016)
					(thickness 0.1524)
				)
				(justify mirror)
			)
		)
		(duplicate_pad_numbers_are_jumpers no)
		(fp_poly
			(pts
				(arc
					(start 0.3556 0)
					(mid -0.3556 0)
					(end 0.3556 0)
				)
			)
			(stroke
				(width 0)
				(type default)
			)
			(fill no)
			(layer "B.CrtYd")
		)
		(fp_poly
			(pts
				(arc
					(start 0.6096 0)
					(mid -0.6096 0)
					(end 0.6096 0)
				)
			)
			(stroke
				(width 0)
				(type default)
			)
			(fill no)
			(layer "B.Fab")
		)
		(pad "1" smd circle
			(at 0 0 180)
			(size 0.7112 0.7112)
			(layers "B.Cu" "B.Mask" "B.Paste")
			(net "ADC_P1V5")
		)
	)
	(footprint ""
		(layer "B.Cu")
		(at 44.802044 -130.345434 90)
		(property "Reference" "R293"
			(at 0 0 90)
			(layer "B.SilkS")
			(hide yes)
			(effects
				(font
					(size 1.27 1.27)
				)
				(justify mirror)
			)
		)
		(property "Value" "0R2J-2-GP"
			(at -0.064008 -3.993896 90)
			(unlocked yes)
			(layer "B.Fab")
			(hide yes)
			(effects
				(font
					(size 1.016 1.016)
					(thickness 0.1524)
				)
				(justify mirror)
			)
		)
		(property "Device Type" "R402H16"
			(at -0.064008 -5.517896 90)
			(unlocked yes)
			(layer "B.Fab")
			(hide yes)
			(effects
				(font
					(size 1.016 1.016)
					(thickness 0.1524)
				)
				(justify mirror)
			)
		)
		(duplicate_pad_numbers_are_jumpers no)
		(fp_line
			(start 0.508 -0.9398)
			(end 0.508 0.9398)
			(stroke
				(width 0.1524)
				(type default)
			)
			(layer "B.SilkS")
		)
		(fp_line
			(start -0.508 -0.9398)
			(end 0.508 -0.9398)
			(stroke
				(width 0.1524)
				(type default)
			)
			(layer "B.SilkS")
		)
		(fp_rect
			(start 0.508 0.9398)
			(end -0.508 -0.9398)
			(stroke
				(width 0)
				(type default)
			)
			(fill no)
			(layer "B.CrtYd")
		)
		(fp_rect
			(start 0.508 0.9398)
			(end -0.508 -0.9398)
			(stroke
				(width 0)
				(type default)
			)
			(fill no)
			(layer "B.Fab")
		)
		(pad "1" smd custom
			(at 0 -0.4445 270)
			(size 0.1397 0.1397)
			(layers "B.Cu" "B.Mask" "B.Paste")
			(net "IOM_FULL_PWR_EN")
			(options
				(clearance outline)
				(anchor circle)
			)
			(primitives
				(gr_poly
					(pts
						(arc
							(start -0.1778 0.2794)
							(mid -0.249642 0.249642)
							(end -0.2794 0.1778)
						)
						(arc
							(start -0.2794 -0.1778)
							(mid -0.249642 -0.249642)
							(end -0.1778 -0.2794)
						)
						(arc
							(start 0.1778 -0.2794)
							(mid 0.249642 -0.249642)
							(end 0.2794 -0.1778)
						)
						(arc
							(start 0.2794 0.1778)
							(mid 0.249642 0.249642)
							(end 0.1778 0.2794)
						)
					)
					(width 0)
					(fill yes)
				)
			)
		)
		(pad "2" smd custom
			(at 0 0.4445 270)
			(size 0.1397 0.1397)
			(layers "B.Cu" "B.Mask" "B.Paste")
			(net "IOM_FULL_PWR_EN_R")
			(options
				(clearance outline)
				(anchor circle)
			)
			(primitives
				(gr_poly
					(pts
						(arc
							(start -0.1778 0.2794)
							(mid -0.249642 0.249642)
							(end -0.2794 0.1778)
						)
						(arc
							(start -0.2794 -0.1778)
							(mid -0.249642 -0.249642)
							(end -0.1778 -0.2794)
						)
						(arc
							(start 0.1778 -0.2794)
							(mid 0.249642 -0.249642)
							(end 0.2794 -0.1778)
						)
						(arc
							(start 0.2794 0.1778)
							(mid 0.249642 0.249642)
							(end 0.1778 0.2794)
						)
					)
					(width 0)
					(fill yes)
				)
			)
		)
	)
	(footprint ""
		(layer "B.Cu")
		(at 212.805264 -87.912956)
		(property "Reference" "R807"
			(at 0 0 0)
			(layer "B.SilkS")
			(hide yes)
			(effects
				(font
					(size 1.27 1.27)
				)
				(justify mirror)
			)
		)
		(property "Value" "4K7R2F-GP"
			(at -0.064008 -3.993896 0)
			(unlocked yes)
			(layer "B.Fab")
			(hide yes)
			(effects
				(font
					(size 1.016 1.016)
					(thickness 0.1524)
				)
				(justify mirror)
			)
		)
		(property "Device Type" "R402H16"
			(at -0.064008 -5.517896 0)
			(unlocked yes)
			(layer "B.Fab")
			(hide yes)
			(effects
				(font
					(size 1.016 1.016)
					(thickness 0.1524)
				)
				(justify mirror)
			)
		)
		(duplicate_pad_numbers_are_jumpers no)
		(fp_line
			(start -0.508 -0.9398)
			(end 0.508 -0.9398)
			(stroke
				(width 0.1524)
				(type default)
			)
			(layer "B.SilkS")
		)
		(fp_line
			(start 0.508 -0.9398)
			(end 0.508 0.9398)
			(stroke
				(width 0.1524)
				(type default)
			)
			(layer "B.SilkS")
		)
		(fp_rect
			(start 0.508 0.9398)
			(end -0.508 -0.9398)
			(stroke
				(width 0)
				(type default)
			)
			(fill no)
			(layer "B.CrtYd")
		)
		(fp_rect
			(start 0.508 0.9398)
			(end -0.508 -0.9398)
			(stroke
				(width 0)
				(type default)
			)
			(fill no)
			(layer "B.Fab")
		)
		(pad "1" smd custom
			(at 0 -0.4445 180)
			(size 0.1397 0.1397)
			(layers "B.Cu" "B.Mask" "B.Paste")
			(net "P3V3_PG")
			(options
				(clearance outline)
				(anchor circle)
			)
			(primitives
				(gr_poly
					(pts
						(arc
							(start -0.1778 0.2794)
							(mid -0.249642 0.249642)
							(end -0.2794 0.1778)
						)
						(arc
							(start -0.2794 -0.1778)
							(mid -0.249642 -0.249642)
							(end -0.1778 -0.2794)
						)
						(arc
							(start 0.1778 -0.2794)
							(mid 0.249642 -0.249642)
							(end 0.2794 -0.1778)
						)
						(arc
							(start 0.2794 0.1778)
							(mid 0.249642 0.249642)
							(end 0.1778 0.2794)
						)
					)
					(width 0)
					(fill yes)
				)
			)
		)
		(pad "2" smd custom
			(at 0 0.4445 180)
			(size 0.1397 0.1397)
			(layers "B.Cu" "B.Mask" "B.Paste")
			(net "P3V3")
			(options
				(clearance outline)
				(anchor circle)
			)
			(primitives
				(gr_poly
					(pts
						(arc
							(start -0.1778 0.2794)
							(mid -0.249642 0.249642)
							(end -0.2794 0.1778)
						)
						(arc
							(start -0.2794 -0.1778)
							(mid -0.249642 -0.249642)
							(end -0.1778 -0.2794)
						)
						(arc
							(start 0.1778 -0.2794)
							(mid 0.249642 -0.249642)
							(end 0.2794 -0.1778)
						)
						(arc
							(start 0.2794 0.1778)
							(mid 0.249642 0.249642)
							(end 0.1778 0.2794)
						)
					)
					(width 0)
					(fill yes)
				)
			)
		)
	)
	(footprint ""
		(layer "B.Cu")
		(at 44.139866 -148.180298 -90)
		(property "Reference" "C55"
			(at 0 0 90)
			(layer "B.SilkS")
			(hide yes)
			(effects
				(font
					(size 1.27 1.27)
				)
				(justify mirror)
			)
		)
		(property "Value" "SCD1U16V2KX-3GP"
			(at -1.1811 -2.7051 270)
			(unlocked yes)
			(layer "B.Fab")
			(hide yes)
			(effects
				(font
					(size 1.016 1.016)
					(thickness 0.1524)
				)
				(justify mirror)
			)
		)
		(property "Device Type" "C402H22"
			(at -1.1811 -4.2291 270)
			(unlocked yes)
			(layer "B.Fab")
			(hide yes)
			(effects
				(font
					(size 1.016 1.016)
					(thickness 0.1524)
				)
				(justify mirror)
			)
		)
		(duplicate_pad_numbers_are_jumpers no)
		(fp_rect
			(start 0.4318 0.9525)
			(end -0.4318 -0.9525)
			(stroke
				(width 0)
				(type default)
			)
			(fill no)
			(layer "B.CrtYd")
		)
		(fp_rect
			(start 0.4318 0.9525)
			(end -0.4318 -0.9525)
			(stroke
				(width 0)
				(type default)
			)
			(fill no)
			(layer "B.Fab")
		)
		(pad "1" smd custom
			(at 0 -0.4445 90)
			(size 0.1524 0.1524)
			(layers "B.Cu" "B.Mask" "B.Paste")
			(net "GND")
			(options
				(clearance outline)
				(anchor circle)
			)
			(primitives
				(gr_poly
					(pts
						(arc
							(start 0.3048 0.2032)
							(mid 0.275042 0.275042)
							(end 0.2032 0.3048)
						)
						(arc
							(start -0.2032 0.3048)
							(mid -0.275042 0.275042)
							(end -0.3048 0.2032)
						)
						(arc
							(start -0.3048 -0.2032)
							(mid -0.275042 -0.275042)
							(end -0.2032 -0.3048)
						)
						(arc
							(start 0.2032 -0.3048)
							(mid 0.275042 -0.275042)
							(end 0.3048 -0.2032)
						)
					)
					(width 0)
					(fill yes)
				)
			)
		)
		(pad "2" smd custom
			(at 0 0.4445 90)
			(size 0.1524 0.1524)
			(layers "B.Cu" "B.Mask" "B.Paste")
			(net "DDR_VREF")
			(options
				(clearance outline)
				(anchor circle)
			)
			(primitives
				(gr_poly
					(pts
						(arc
							(start 0.3048 0.2032)
							(mid 0.275042 0.275042)
							(end 0.2032 0.3048)
						)
						(arc
							(start -0.2032 0.3048)
							(mid -0.275042 0.275042)
							(end -0.3048 0.2032)
						)
						(arc
							(start -0.3048 -0.2032)
							(mid -0.275042 -0.275042)
							(end -0.2032 -0.3048)
						)
						(arc
							(start 0.2032 -0.3048)
							(mid 0.275042 -0.275042)
							(end 0.3048 -0.2032)
						)
					)
					(width 0)
					(fill yes)
				)
			)
		)
	)
)
